# TIMECARD (Time Appliance Project (Time Card)) — schematic netlist excerpt (pin names and nets, part order shuffled) for the footprints in the layout excerpt that follows; sources: Cadence DE-HDL packaged netlist, KiCad conversion of R4006-B0001-02_R01.brd

C177  CAPACITOR  100UF 6.3V 20%  pkg SMC_1210R_H110  page 14 : \1\ = XP1R0V_FPGA_VCCINT ; \2\ = SG
R98  RESISTOR  0OHM -  pkg SMC_0402R_H016  page 21 : \1\ = R_MAC_USB_DM ; \2\ = MUX_USB_DM

(kicad_pcb
	(version 20260206)
	(generator "pcbnew")
	(generator_version "10.0")
	(general
		(thickness 1.6)
		(legacy_teardrops no)
	)
	(paper "A4")
	(title_block
		(title "timecard-production-celestica-r4006 — R4006-B0001-02_R01.brd")
		(comment 1 "Time Appliance Project (Time Card) / footprints 613-614 of 1113")
	)
	(layers
		(0 "F.Cu" signal "TOP")
		(4 "In1.Cu" signal "L02_GND1")
		(6 "In2.Cu" signal "L03_SIG1")
		(8 "In3.Cu" signal "L04_GND2")
		(10 "In4.Cu" signal "L05_VCC1")
		(12 "In5.Cu" signal "L06_VCC2")
		(14 "In6.Cu" signal "L07_GND3")
		(16 "In7.Cu" signal "L08_SIG2")
		(18 "In8.Cu" signal "L09_GND4")
		(2 "B.Cu" signal "BOTTOM")
		(9 "F.Adhes" user "F.Adhesive")
		(11 "B.Adhes" user "B.Adhesive")
		(13 "F.Paste" user "Package Geometry/Pastemask Top")
		(15 "B.Paste" user "Package Geometry/Pastemask Bottom")
		(5 "F.SilkS" user "Ref Des/Silkscreen Top")
		(7 "B.SilkS" user "Ref Des/Silkscreen Bottom")
		(1 "F.Mask" user "Board Geometry/Soldermask Top")
		(3 "B.Mask" user "Board Geometry/Soldermask Bottom")
		(17 "Dwgs.User" user "User.Drawings")
		(19 "Cmts.User" user "User.Comments")
		(21 "Eco1.User" user "User.Eco1")
		(23 "Eco2.User" user "User.Eco2")
		(25 "Edge.Cuts" user "Board Geometry/Outline")
		(27 "Margin" user)
		(31 "F.CrtYd" user "Package Geometry/Place Bound Top")
		(29 "B.CrtYd" user "Package Geometry/Place Bound Bottom")
		(35 "F.Fab" user "Ref Des/Assembly Top")
		(33 "B.Fab" user "Ref Des/Assembly Bottom")
	)
	(footprint ""
		(layer "F.Cu")
		(at 79.756 -46.99)
		(property "Reference" "R98"
			(at 0.127 14.13637 0)
			(unlocked yes)
			(layer "F.SilkS")
			(effects
				(font
					(size 0.7874 0.5842)
					(thickness 0.1524)
				)
			)
		)
		(property "Value" "VAL*"
			(at 0.02032 2.13233 0)
			(unlocked yes)
			(layer "F.Fab")
			(hide yes)
			(effects
				(font
					(size 0.7874 0.5842)
					(thickness 0.1524)
				)
			)
		)
		(property "Device Type" "RESISTOR-G155-100R0-J0,0OHM,-"
			(at 0.008382 1.210564 0)
			(unlocked yes)
			(layer "F.Fab")
			(hide yes)
			(effects
				(font
					(size 0.7874 0.5842)
					(thickness 0.1524)
				)
			)
		)
		(property "User Part Number" "PARTNUM*"
			(at 0.02032 4.024884 0)
			(unlocked yes)
			(layer "Cmts.User")
			(hide yes)
			(effects
				(font
					(size 0.7874 0.5842)
					(thickness 0.1524)
				)
			)
		)
		(property "Tolerance" "TOL*"
			(at 0.044704 3.05435 0)
			(unlocked yes)
			(layer "Cmts.User")
			(hide yes)
			(effects
				(font
					(size 0.7874 0.5842)
					(thickness 0.1524)
				)
			)
		)
		(duplicate_pad_numbers_are_jumpers no)
		(fp_line
			(start -1.143 -0.5588)
			(end -1.143 0.5588)
			(stroke
				(width 0.1)
				(type default)
			)
			(layer "F.SilkS")
		)
		(fp_line
			(start -1.143 0.5588)
			(end 1.143 0.5588)
			(stroke
				(width 0.1)
				(type default)
			)
			(layer "F.SilkS")
		)
		(fp_line
			(start 1.143 -0.5588)
			(end -1.143 -0.5588)
			(stroke
				(width 0.1)
				(type default)
			)
			(layer "F.SilkS")
		)
		(fp_line
			(start 1.143 0.5588)
			(end 1.143 -0.5588)
			(stroke
				(width 0.1)
				(type default)
			)
			(layer "F.SilkS")
		)
		(fp_poly
			(pts
				(xy -1.143 0.5588) (xy 1.143 0.5588) (xy 1.143 -0.5588) (xy -1.143 -0.5588)
			)
			(stroke
				(width 0)
				(type default)
			)
			(fill no)
			(layer "F.CrtYd")
		)
		(fp_line
			(start -0.508 -0.3048)
			(end -0.508 0.3048)
			(stroke
				(width 0.1)
				(type default)
			)
			(layer "F.Fab")
		)
		(fp_line
			(start -0.508 0.3048)
			(end 0.508 0.3048)
			(stroke
				(width 0.1)
				(type default)
			)
			(layer "F.Fab")
		)
		(fp_line
			(start 0.508 -0.3048)
			(end -0.508 -0.3048)
			(stroke
				(width 0.1)
				(type default)
			)
			(layer "F.Fab")
		)
		(fp_line
			(start 0.508 0.3048)
			(end 0.508 -0.3048)
			(stroke
				(width 0.1)
				(type default)
			)
			(layer "F.Fab")
		)
		(pad "1" smd rect
			(at -0.5334 0)
			(size 0.7112 0.6096)
			(layers "F.Cu" "F.Mask" "F.Paste")
			(net "R_MAC_USB_DM")
		)
		(pad "2" smd rect
			(at 0.5334 0)
			(size 0.7112 0.6096)
			(layers "F.Cu" "F.Mask" "F.Paste")
			(net "MUX_USB_DM")
		)
		(zone
			(layer "F.Cu")
			(hatch none 0.5)
			(connect_pads
				(clearance 0)
			)
			(min_thickness 0.25)
			(keepout
				(tracks not_allowed)
				(vias allowed)
				(pads allowed)
				(copperpour not_allowed)
				(footprints allowed)
			)
			(placement
				(enabled no)
				(sheetname "")
			)
			(fill
				(thermal_gap 0.5)
				(thermal_bridge_width 0.5)
				(island_removal_mode 0)
			)
			(polygon
				(pts
					(xy 79.6798 -46.6852) (xy 79.8322 -46.6852) (xy 79.8322 -47.2948) (xy 79.6798 -47.2948)
				)
			)
		)
		(zone
			(layer "F.Cu")
			(hatch none 0.5)
			(connect_pads
				(clearance 0)
			)
			(min_thickness 0.25)
			(keepout
				(tracks allowed)
				(vias not_allowed)
				(pads allowed)
				(copperpour not_allowed)
				(footprints allowed)
			)
			(placement
				(enabled no)
				(sheetname "")
			)
			(fill
				(thermal_gap 0.5)
				(thermal_bridge_width 0.5)
				(island_removal_mode 0)
			)
			(polygon
				(pts
					(xy 79.6798 -46.6852) (xy 79.8322 -46.6852) (xy 79.8322 -47.2948) (xy 79.6798 -47.2948)
				)
			)
		)
	)
	(footprint ""
		(layer "F.Cu")
		(at 133.223 -37.338)
		(property "Reference" "C177"
			(at 4.445 3.97637 0)
			(unlocked yes)
			(layer "F.SilkS")
			(effects
				(font
					(size 0.7874 0.5842)
					(thickness 0.1524)
				)
			)
		)
		(property "Value" "VAL*"
			(at 0.1016 3.769106 0)
			(unlocked yes)
			(layer "F.Fab")
			(hide yes)
			(effects
				(font
					(size 0.7874 0.5842)
					(thickness 0.1524)
				)
			)
		)
		(property "Tolerance" "TOL*"
			(at 0.127 4.734306 0)
			(unlocked yes)
			(layer "Cmts.User")
			(hide yes)
			(effects
				(font
					(size 0.7874 0.5842)
					(thickness 0.1524)
				)
			)
		)
		(property "User Part Number" "PARTNUM*"
			(at 0.2032 5.801106 0)
			(unlocked yes)
			(layer "Cmts.User")
			(hide yes)
			(effects
				(font
					(size 0.7874 0.5842)
					(thickness 0.1524)
				)
			)
		)
		(property "Device Type" "CAPACITOR-G109-0G107-BM,100UF,A"
			(at 0.0762 2.829306 0)
			(unlocked yes)
			(layer "F.Fab")
			(hide yes)
			(effects
				(font
					(size 0.7874 0.5842)
					(thickness 0.1524)
				)
			)
		)
		(duplicate_pad_numbers_are_jumpers no)
		(fp_line
			(start -2.159 -1.5748)
			(end 2.159 -1.5748)
			(stroke
				(width 0.1)
				(type default)
			)
			(layer "F.SilkS")
		)
		(fp_line
			(start -2.159 1.5748)
			(end -2.159 -1.5748)
			(stroke
				(width 0.1)
				(type default)
			)
			(layer "F.SilkS")
		)
		(fp_line
			(start 2.159 -1.5748)
			(end 2.159 1.5748)
			(stroke
				(width 0.1)
				(type default)
			)
			(layer "F.SilkS")
		)
		(fp_line
			(start 2.159 1.5748)
			(end -2.159 1.5748)
			(stroke
				(width 0.1)
				(type default)
			)
			(layer "F.SilkS")
		)
		(fp_rect
			(start -2.159 -1.5748)
			(end 2.159 1.5748)
			(stroke
				(width 0)
				(type default)
			)
			(fill no)
			(layer "F.CrtYd")
		)
		(fp_line
			(start -1.6002 -1.2446)
			(end -1.6002 1.2446)
			(stroke
				(width 0.1)
				(type default)
			)
			(layer "F.Fab")
		)
		(fp_line
			(start -1.6002 1.2446)
			(end 1.6002 1.2446)
			(stroke
				(width 0.1)
				(type default)
			)
			(layer "F.Fab")
		)
		(fp_line
			(start 1.6002 -1.2446)
			(end -1.6002 -1.2446)
			(stroke
				(width 0.1)
				(type default)
			)
			(layer "F.Fab")
		)
		(fp_line
			(start 1.6002 1.2446)
			(end 1.6002 -1.2446)
			(stroke
				(width 0.1)
				(type default)
			)
			(layer "F.Fab")
		)
		(pad "1" smd rect
			(at -1.3335 0)
			(size 1.143 2.6416)
			(layers "F.Cu" "F.Mask" "F.Paste")
			(net "XP1R0V_FPGA_VCCINT")
		)
		(pad "2" smd rect
			(at 1.3335 0)
			(size 1.143 2.6416)
			(layers "F.Cu" "F.Mask" "F.Paste")
			(net "SG")
		)
		(zone
			(layer "F.Cu")
			(hatch none 0.5)
			(connect_pads
				(clearance 0)
			)
			(min_thickness 0.25)
			(keepout
				(tracks allowed)
				(vias not_allowed)
				(pads allowed)
				(copperpour not_allowed)
				(footprints allowed)
			)
			(placement
				(enabled no)
				(sheetname "")
			)
			(fill
				(thermal_gap 0.5)
				(thermal_bridge_width 0.5)
				(island_removal_mode 0)
			)
			(polygon
				(pts
					(xy 132.5372 -38.735) (xy 132.5372 -35.941) (xy 133.9088 -35.941) (xy 133.9088 -38.735)
				)
			)
		)
	)
)
